# BASEBOARD_FAB2 (Tioga Pass) — schematic netlist excerpt (pin names and nets, part order shuffled) for the footprints in the layout excerpt that follows; sources: Cadence DE-HDL packaged netlist, KiCad conversion of Wiwynn_Tioga_Pass_MB.brd

U2T3  TTL1G32_A  74LVC1G32 IC  pkg SOT  page 154
  A  = FM_DUAL_BIOS_SEL_N
  B  = SPI_SWITCH_CS0_N
  Y  = SPI_CS0_PRIMARY_N

R2L12  RES  2.0K 1% CHIP  pkg 0402  page 178 : A = P3V3_STBY ; B = SGPIO_PCH_SATA_LOAD_R
C2N12  CAP_A  1.0UF 6.3V 10% X6S  pkg 0402V  page 132 : A = PVNN_PCH_STBY ; B = GND

(kicad_pcb
	(version 20260206)
	(generator "pcbnew")
	(generator_version "10.0")
	(general
		(thickness 1.6)
		(legacy_teardrops no)
	)
	(paper "A4")
	(title_block
		(title "Wiwynn_Tioga_Pass_MB.brd")
		(comment 1 "Tioga Pass / footprints 3646-3648 of 4770")
	)
	(layers
		(0 "F.Cu" signal "TOP")
		(4 "In1.Cu" signal "L2GND")
		(6 "In2.Cu" signal "L3")
		(8 "In3.Cu" signal "L4GND")
		(10 "In4.Cu" signal "L5")
		(12 "In5.Cu" signal "L6GND")
		(14 "In6.Cu" signal "L7VCC")
		(16 "In7.Cu" signal "L8VCC")
		(18 "In8.Cu" signal "L9GND")
		(20 "In9.Cu" signal "L10")
		(22 "In10.Cu" signal "L11GND")
		(24 "In11.Cu" signal "L12")
		(26 "In12.Cu" signal "L13GND")
		(2 "B.Cu" signal "BOTTOM")
		(9 "F.Adhes" user "F.Adhesive")
		(11 "B.Adhes" user "B.Adhesive")
		(13 "F.Paste" user "Package Geometry/Pastemask Top")
		(15 "B.Paste" user "Package Geometry/Pastemask Bottom")
		(5 "F.SilkS" user "Ref Des/Silkscreen Top")
		(7 "B.SilkS" user "Ref Des/Silkscreen Bottom")
		(1 "F.Mask" user "Board Geometry/Soldermask Top")
		(3 "B.Mask" user "Board Geometry/Soldermask Bottom")
		(17 "Dwgs.User" user "User.Drawings")
		(19 "Cmts.User" user "User.Comments")
		(21 "Eco1.User" user "User.Eco1")
		(23 "Eco2.User" user "User.Eco2")
		(25 "Edge.Cuts" user "Board Geometry/Outline")
		(27 "Margin" user)
		(31 "F.CrtYd" user "Package Geometry/Place Bound Top")
		(29 "B.CrtYd" user "Package Geometry/Place Bound Bottom")
		(35 "F.Fab" user "Ref Des/Assembly Top")
		(33 "B.Fab" user "Ref Des/Assembly Bottom")
	)
	(footprint ""
		(layer "B.Cu")
		(at 390.4742 -61.7728 180)
		(property "Reference" "U2T3"
			(at 5.31368 1.00711 180)
			(unlocked yes)
			(layer "B.SilkS")
			(effects
				(font
					(size 0.7874 0.5842)
					(thickness 0.1524)
				)
				(justify left mirror)
			)
		)
		(property "Value" ""
			(at 0 0 0)
			(layer "B.Fab")
			(effects
				(font
					(size 1.27 1.27)
				)
				(justify mirror)
			)
		)
		(duplicate_pad_numbers_are_jumpers no)
		(fp_circle
			(center 0.4699 -0.8382)
			(end 0.3429 -0.8382)
			(stroke
				(width 0.254)
				(type default)
			)
			(fill no)
			(layer "B.SilkS")
		)
		(fp_poly
			(pts
				(xy -0.21463 -0.450088) (xy -1.56337 -0.450088) (xy -1.56337 1.75006) (xy -0.21463 1.75006)
			)
			(stroke
				(width 0)
				(type default)
			)
			(fill no)
			(layer "B.CrtYd")
		)
		(fp_line
			(start -0.21463 1.75006)
			(end -0.21463 -0.450088)
			(stroke
				(width 0.1)
				(type default)
			)
			(layer "B.Fab")
		)
		(fp_line
			(start -0.21463 -0.450088)
			(end -1.56337 -0.450088)
			(stroke
				(width 0.1)
				(type default)
			)
			(layer "B.Fab")
		)
		(fp_line
			(start -1.56337 1.75006)
			(end -0.21463 1.75006)
			(stroke
				(width 0.1)
				(type default)
			)
			(layer "B.Fab")
		)
		(fp_line
			(start -1.56337 -0.450088)
			(end -1.56337 1.75006)
			(stroke
				(width 0.1)
				(type default)
			)
			(layer "B.Fab")
		)
		(fp_circle
			(center 0.4699 -0.8382)
			(end 0.3429 -0.8382)
			(stroke
				(width 0.254)
				(type default)
			)
			(fill no)
			(layer "B.Fab")
		)
		(pad "1" smd rect
			(at 0 0)
			(size 1.016 0.381)
			(layers "B.Cu" "B.Mask" "B.Paste")
			(net "FM_DUAL_BIOS_SEL_N")
		)
		(pad "2" smd rect
			(at 0 0.649986)
			(size 1.016 0.381)
			(layers "B.Cu" "B.Mask" "B.Paste")
			(net "SPI_SWITCH_CS0_N")
		)
		(pad "3" smd rect
			(at 0 1.299972)
			(size 1.016 0.381)
			(layers "B.Cu" "B.Mask" "B.Paste")
			(net "GND")
		)
		(pad "4" smd rect
			(at -1.778 1.299972)
			(size 1.016 0.381)
			(layers "B.Cu" "B.Mask" "B.Paste")
			(net "SPI_CS0_PRIMARY_N")
		)
		(pad "5" smd rect
			(at -1.778 0)
			(size 1.016 0.381)
			(layers "B.Cu" "B.Mask" "B.Paste")
			(net "P3V3_STBY")
		)
	)
	(footprint ""
		(layer "B.Cu")
		(at 390.13765 -107.85475)
		(property "Reference" "C2N12"
			(at 0 0 0)
			(layer "B.SilkS")
			(hide yes)
			(effects
				(font
					(size 1.27 1.27)
				)
				(justify mirror)
			)
		)
		(property "Value" ""
			(at 0 0 0)
			(layer "B.Fab")
			(effects
				(font
					(size 1.27 1.27)
				)
				(justify mirror)
			)
		)
		(duplicate_pad_numbers_are_jumpers no)
		(fp_rect
			(start 0.2794 0.9144)
			(end -0.2794 -0.1143)
			(stroke
				(width 0)
				(type default)
			)
			(fill no)
			(layer "B.CrtYd")
		)
		(fp_line
			(start -0.2794 -0.1143)
			(end -0.2794 0.9144)
			(stroke
				(width 0.1)
				(type default)
			)
			(layer "B.Fab")
		)
		(fp_line
			(start -0.2794 0.9144)
			(end 0.2794 0.9144)
			(stroke
				(width 0.1)
				(type default)
			)
			(layer "B.Fab")
		)
		(fp_line
			(start 0.2794 -0.1143)
			(end -0.2794 -0.1143)
			(stroke
				(width 0.1)
				(type default)
			)
			(layer "B.Fab")
		)
		(fp_line
			(start 0.2794 0.9144)
			(end 0.2794 -0.1143)
			(stroke
				(width 0.1)
				(type default)
			)
			(layer "B.Fab")
		)
		(pad "1" smd custom
			(at 0 0 270)
			(size 0.10414 0.10414)
			(layers "B.Cu" "B.Mask" "B.Paste")
			(net "PVNN_PCH_STBY")
			(options
				(clearance outline)
				(anchor circle)
			)
			(primitives
				(gr_poly
					(pts
						(xy -0.20828 -0.08636) (xy -0.20828 0.08636) (xy -0.08636 0.20828) (xy 0.086614 0.20828) (xy 0.20828 0.086614)
						(xy 0.20828 -0.08636) (xy 0.08636 -0.20828) (xy -0.08636 -0.20828)
					)
					(width 0)
					(fill yes)
				)
			)
		)
		(pad "2" smd custom
			(at 0 0.8001 270)
			(size 0.10414 0.10414)
			(layers "B.Cu" "B.Mask" "B.Paste")
			(net "GND")
			(options
				(clearance outline)
				(anchor circle)
			)
			(primitives
				(gr_poly
					(pts
						(xy -0.20828 -0.08636) (xy -0.20828 0.08636) (xy -0.08636 0.20828) (xy 0.086614 0.20828) (xy 0.20828 0.086614)
						(xy 0.20828 -0.08636) (xy 0.08636 -0.20828) (xy -0.08636 -0.20828)
					)
					(width 0)
					(fill yes)
				)
			)
		)
		(zone
			(layer "B.Cu")
			(hatch none 0.5)
			(connect_pads
				(clearance 0)
			)
			(min_thickness 0.25)
			(keepout
				(tracks not_allowed)
				(vias allowed)
				(pads allowed)
				(copperpour not_allowed)
				(footprints allowed)
			)
			(placement
				(enabled no)
				(sheetname "")
			)
			(fill
				(thermal_gap 0.5)
				(thermal_bridge_width 0.5)
				(island_removal_mode 0)
			)
			(polygon
				(pts
					(xy 390.22528 -107.6452) (xy 390.22528 -107.2642) (xy 390.05002 -107.2642) (xy 390.049766 -107.6452)
				)
			)
		)
		(zone
			(layer "B.Cu")
			(hatch none 0.5)
			(connect_pads
				(clearance 0)
			)
			(min_thickness 0.25)
			(keepout
				(tracks allowed)
				(vias not_allowed)
				(pads allowed)
				(copperpour not_allowed)
				(footprints allowed)
			)
			(placement
				(enabled no)
				(sheetname "")
			)
			(fill
				(thermal_gap 0.5)
				(thermal_bridge_width 0.5)
				(island_removal_mode 0)
			)
			(polygon
				(pts
					(xy 390.22528 -107.6452) (xy 390.22528 -107.2642) (xy 390.05002 -107.2642) (xy 390.049766 -107.6452)
				)
			)
		)
	)
	(footprint ""
		(layer "B.Cu")
		(at 433.578 -152.4 -90)
		(property "Reference" "R2L12"
			(at 0 0 90)
			(layer "B.SilkS")
			(hide yes)
			(effects
				(font
					(size 1.27 1.27)
				)
				(justify mirror)
			)
		)
		(property "Value" ""
			(at 0 0 90)
			(layer "B.Fab")
			(effects
				(font
					(size 1.27 1.27)
				)
				(justify mirror)
			)
		)
		(duplicate_pad_numbers_are_jumpers no)
		(fp_poly
			(pts
				(xy 0.2794 -0.1016) (xy -0.2794 -0.1016) (xy -0.2794 0.9906) (xy 0.2794 0.9906)
			)
			(stroke
				(width 0)
				(type default)
			)
			(fill no)
			(layer "B.CrtYd")
		)
		(fp_line
			(start -0.2794 0.9906)
			(end -0.2794 -0.1016)
			(stroke
				(width 0.1)
				(type default)
			)
			(layer "B.Fab")
		)
		(fp_line
			(start 0.2794 0.9906)
			(end -0.2794 0.9906)
			(stroke
				(width 0.1)
				(type default)
			)
			(layer "B.Fab")
		)
		(fp_line
			(start -0.2794 -0.1016)
			(end 0.2794 -0.1016)
			(stroke
				(width 0.1)
				(type default)
			)
			(layer "B.Fab")
		)
		(fp_line
			(start 0.2794 -0.1016)
			(end 0.2794 0.9906)
			(stroke
				(width 0.1)
				(type default)
			)
			(layer "B.Fab")
		)
		(pad "1" smd rect
			(at 0 0 90)
			(size 0.508 0.508)
			(layers "B.Cu" "B.Mask" "B.Paste")
			(net "P3V3_STBY")
		)
		(pad "2" smd rect
			(at 0 0.889 90)
			(size 0.508 0.508)
			(layers "B.Cu" "B.Mask" "B.Paste")
			(net "SGPIO_PCH_SATA_LOAD_R")
		)
		(zone
			(layer "B.Cu")
			(hatch none 0.5)
			(connect_pads
				(clearance 0)
			)
			(min_thickness 0.25)
			(keepout
				(tracks not_allowed)
				(vias allowed)
				(pads allowed)
				(copperpour not_allowed)
				(footprints allowed)
			)
			(placement
				(enabled no)
				(sheetname "")
			)
			(fill
				(thermal_gap 0.5)
				(thermal_bridge_width 0.5)
				(island_removal_mode 0)
			)
			(polygon
				(pts
					(xy 432.943 -152.146) (xy 432.943 -152.654) (xy 433.324 -152.654) (xy 433.324 -152.146)
				)
			)
		)
		(zone
			(layer "B.Cu")
			(hatch none 0.5)
			(connect_pads
				(clearance 0)
			)
			(min_thickness 0.25)
			(keepout
				(tracks allowed)
				(vias not_allowed)
				(pads allowed)
				(copperpour not_allowed)
				(footprints allowed)
			)
			(placement
				(enabled no)
				(sheetname "")
			)
			(fill
				(thermal_gap 0.5)
				(thermal_bridge_width 0.5)
				(island_removal_mode 0)
			)
			(polygon
				(pts
					(xy 433.324 -152.146) (xy 433.324 -152.654) (xy 432.943 -152.654) (xy 432.943 -152.146)
				)
			)
		)
	)
)
